(kicad_pcb
	(version 20260206)
	(generator "pcbnew")
	(generator_version "10.0")
	(general
		(thickness 1.6)
		(legacy_teardrops no)
	)
	(paper "A4")
	(title_block
		(title "04192023_DAF0TMB3IC0_F0TG_MB_C_brd_V02_OCP.brd")
		(comment 1 "Grand Teton / footprint 3955 of 8354 (U25), pads 4000-4109 of 6102")
	)
	(layers
		(0 "F.Cu" signal "TOP")
		(4 "In1.Cu" signal "GND")
		(6 "In2.Cu" signal "IN1")
		(8 "In3.Cu" signal "GND1")
		(10 "In4.Cu" signal "IN2")
		(12 "In5.Cu" signal "GND2")
		(14 "In6.Cu" signal "IN3")
		(16 "In7.Cu" signal "GND3")
		(18 "In8.Cu" signal "VCC")
		(20 "In9.Cu" signal "VCC1")
		(22 "In10.Cu" signal "GND4")
		(24 "In11.Cu" signal "IN4")
		(26 "In12.Cu" signal "GND5")
		(28 "In13.Cu" signal "IN5")
		(30 "In14.Cu" signal "GND6")
		(32 "In15.Cu" signal "IN6")
		(34 "In16.Cu" signal "GND7")
		(2 "B.Cu" signal "BOTTOM")
		(9 "F.Adhes" user "F.Adhesive")
		(11 "B.Adhes" user "B.Adhesive")
		(13 "F.Paste" user "Package Geometry/Pastemask Top")
		(15 "B.Paste" user "Package Geometry/Pastemask Bottom")
		(5 "F.SilkS" user "Ref Des/Silkscreen Top")
		(7 "B.SilkS" user "Ref Des/Silkscreen Bottom")
		(1 "F.Mask" user "Board Geometry/Soldermask Top")
		(3 "B.Mask" user "Board Geometry/Soldermask Bottom")
		(17 "Dwgs.User" user "User.Drawings")
		(19 "Cmts.User" user "User.Comments")
		(21 "Eco1.User" user "User.Eco1")
		(23 "Eco2.User" user "User.Eco2")
		(25 "Edge.Cuts" user "Board Geometry/Outline")
		(27 "Margin" user)
		(31 "F.CrtYd" user "Package Geometry/Place Bound Top")
		(29 "B.CrtYd" user "Package Geometry/Place Bound Bottom")
		(35 "F.Fab" user "Ref Des/Assembly Top")
		(33 "B.Fab" user "Ref Des/Assembly Bottom")
	)
	(footprint ""
		(layer "F.Cu")
		(at 359.867962 -258.880102 180)
		(property "Reference" "U25"
			(at -45.78477 -62.086744 0)
			(unlocked yes)
			(layer "F.SilkS")
			(effects
				(font
					(size 0.7874 0.5842)
					(thickness 0.1524)
				)
			)
		)
		(property "Value" ""
			(at 0 0 180)
			(layer "F.Fab")
			(effects
				(font
					(size 1.27 1.27)
				)
			)
		)
		(duplicate_pad_numbers_are_jumpers no)
		(pad "CU43" smd circle
			(at 4.080002 27.090116 180)
			(size 0.450088 0.450088)
			(layers "F.Cu" "F.Mask" "F.Paste")
			(net "P5E_CPU0_P0_TX_DN<11>")
		)
		(pad "CU44" smd circle
			(at 5.020056 27.090116 180)
			(size 0.450088 0.450088)
			(layers "F.Cu" "F.Mask" "F.Paste")
			(net "P5E_CPU0_P0_TX_DP<11>")
		)
		(pad "CU45" smd circle
			(at 5.96011 27.090116 180)
			(size 0.450088 0.450088)
			(layers "F.Cu" "F.Mask" "F.Paste")
			(net "GND")
		)
		(pad "CU46" smd circle
			(at 6.89991 27.090116 180)
			(size 0.450088 0.450088)
			(layers "F.Cu" "F.Mask" "F.Paste")
			(net "P5E_CPU0_P0_TX_DN<8>")
		)
		(pad "CU47" smd circle
			(at 7.839964 27.090116 180)
			(size 0.450088 0.450088)
			(layers "F.Cu" "F.Mask" "F.Paste")
			(net "P5E_CPU0_P0_TX_DP<8>")
		)
		(pad "CU48" smd circle
			(at 8.780018 27.090116 180)
			(size 0.450088 0.450088)
			(layers "F.Cu" "F.Mask" "F.Paste")
			(net "GND")
		)
		(pad "CU49" smd circle
			(at 9.720072 27.090116 180)
			(size 0.450088 0.450088)
			(layers "F.Cu" "F.Mask" "F.Paste")
			(net "P5E_CPU0_P0_TX_DN<5>")
		)
		(pad "CU50" smd circle
			(at 10.659872 27.090116 180)
			(size 0.450088 0.450088)
			(layers "F.Cu" "F.Mask" "F.Paste")
			(net "P5E_CPU0_P0_TX_DP<5>")
		)
		(pad "CU51" smd circle
			(at 11.599926 27.090116 180)
			(size 0.450088 0.450088)
			(layers "F.Cu" "F.Mask" "F.Paste")
			(net "GND")
		)
		(pad "CU52" smd circle
			(at 12.53998 27.090116 180)
			(size 0.450088 0.450088)
			(layers "F.Cu" "F.Mask" "F.Paste")
			(net "P5E_CPU0_P1_TX_DN<0>")
		)
		(pad "CU53" smd circle
			(at 13.480034 27.090116 180)
			(size 0.450088 0.450088)
			(layers "F.Cu" "F.Mask" "F.Paste")
			(net "P5E_CPU0_P1_TX_DP<0>")
		)
		(pad "CU54" smd circle
			(at 14.420088 27.090116 180)
			(size 0.450088 0.450088)
			(layers "F.Cu" "F.Mask" "F.Paste")
			(net "GND")
		)
		(pad "CU55" smd circle
			(at 15.359888 27.090116 180)
			(size 0.450088 0.450088)
			(layers "F.Cu" "F.Mask" "F.Paste")
			(net "M_C_CPU0_SB_DQS_DN<7>")
		)
		(pad "CU56" smd circle
			(at 16.299942 27.090116 180)
			(size 0.450088 0.450088)
			(layers "F.Cu" "F.Mask" "F.Paste")
			(net "GND")
		)
		(pad "CU57" smd circle
			(at 17.239996 27.090116 180)
			(size 0.450088 0.450088)
			(layers "F.Cu" "F.Mask" "F.Paste")
			(net "M_C_CPU0_SB_DQS_DN<2>")
		)
		(pad "CU58" smd circle
			(at 18.18005 27.090116 180)
			(size 0.450088 0.450088)
			(layers "F.Cu" "F.Mask" "F.Paste")
			(net "GND")
		)
		(pad "CU59" smd circle
			(at 19.120104 27.090116 180)
			(size 0.450088 0.450088)
			(layers "F.Cu" "F.Mask" "F.Paste")
			(net "M_D_CPU0_SB_DQS_DN<7>")
		)
		(pad "CU60" smd circle
			(at 20.059904 27.090116 180)
			(size 0.450088 0.450088)
			(layers "F.Cu" "F.Mask" "F.Paste")
			(net "M_D_CPU0_SB_DQS_DN<2>")
		)
		(pad "CU61" smd circle
			(at 20.999958 27.090116 180)
			(size 0.450088 0.450088)
			(layers "F.Cu" "F.Mask" "F.Paste")
			(net "GND")
		)
		(pad "CU62" smd circle
			(at 21.940012 27.090116 180)
			(size 0.450088 0.450088)
			(layers "F.Cu" "F.Mask" "F.Paste")
			(net "M_B_CPU0_SB_DQS_DN<7>")
		)
		(pad "CU63" smd circle
			(at 22.880066 27.090116 180)
			(size 0.450088 0.450088)
			(layers "F.Cu" "F.Mask" "F.Paste")
			(net "GND")
		)
		(pad "CU64" smd circle
			(at 23.82012 27.090116 180)
			(size 0.450088 0.450088)
			(layers "F.Cu" "F.Mask" "F.Paste")
			(net "M_B_CPU0_SB_DQS_DN<2>")
		)
		(pad "CU65" smd circle
			(at 24.75992 27.090116 180)
			(size 0.450088 0.450088)
			(layers "F.Cu" "F.Mask" "F.Paste")
			(net "GND")
		)
		(pad "CU66" smd circle
			(at 25.699974 27.090116 180)
			(size 0.450088 0.450088)
			(layers "F.Cu" "F.Mask" "F.Paste")
			(net "M_F_CPU0_SB_DQS_DN<7>")
		)
		(pad "CU67" smd circle
			(at 26.640028 27.090116 180)
			(size 0.450088 0.450088)
			(layers "F.Cu" "F.Mask" "F.Paste")
			(net "M_F_CPU0_SB_DQS_DN<2>")
		)
		(pad "CU68" smd circle
			(at 27.580082 27.090116 180)
			(size 0.450088 0.450088)
			(layers "F.Cu" "F.Mask" "F.Paste")
			(net "GND")
		)
		(pad "CU69" smd circle
			(at 28.519882 27.090116 180)
			(size 0.450088 0.450088)
			(layers "F.Cu" "F.Mask" "F.Paste")
			(net "M_E_CPU0_SB_DQS_DN<7>")
		)
		(pad "CU70" smd circle
			(at 29.459936 27.090116 180)
			(size 0.450088 0.450088)
			(layers "F.Cu" "F.Mask" "F.Paste")
			(net "GND")
		)
		(pad "CU71" smd circle
			(at 30.39999 27.090116 180)
			(size 0.450088 0.450088)
			(layers "F.Cu" "F.Mask" "F.Paste")
			(net "M_E_CPU0_SB_DQS_DN<2>")
		)
		(pad "CU72" smd circle
			(at 31.340044 27.090116 180)
			(size 0.450088 0.450088)
			(layers "F.Cu" "F.Mask" "F.Paste")
			(net "GND")
		)
		(pad "CU73" smd circle
			(at 32.280098 27.090116 180)
			(size 0.450088 0.450088)
			(layers "F.Cu" "F.Mask" "F.Paste")
			(net "M_A_CPU0_SB_DQS_DN<7>")
		)
		(pad "CU74" smd circle
			(at 33.219898 27.090116 180)
			(size 0.450088 0.450088)
			(layers "F.Cu" "F.Mask" "F.Paste")
			(net "M_A_CPU0_SB_DQS_DN<2>")
		)
		(pad "CU75" smd circle
			(at 34.159952 27.090116 180)
			(size 0.450088 0.450088)
			(layers "F.Cu" "F.Mask" "F.Paste")
			(net "GND")
		)
		(pad "CV2" smd circle
			(at -33.990026 27.900122 180)
			(size 0.450088 0.450088)
			(layers "F.Cu" "F.Mask" "F.Paste")
			(net "M_G_CPU0_SB_DQ<20>")
		)
		(pad "CV3" smd circle
			(at -33.049972 27.900122 180)
			(size 0.450088 0.450088)
			(layers "F.Cu" "F.Mask" "F.Paste")
			(net "GND")
		)
		(pad "CV4" smd circle
			(at -32.109918 27.900122 180)
			(size 0.450088 0.450088)
			(layers "F.Cu" "F.Mask" "F.Paste")
			(net "M_G_CPU0_SB_DQS_DP<7>")
		)
		(pad "CV5" smd circle
			(at -31.170118 27.900122 180)
			(size 0.450088 0.450088)
			(layers "F.Cu" "F.Mask" "F.Paste")
			(net "GND")
		)
		(pad "CV6" smd circle
			(at -30.230064 27.900122 180)
			(size 0.450088 0.450088)
			(layers "F.Cu" "F.Mask" "F.Paste")
			(net "M_K_CPU0_SB_DQ<20>")
		)
		(pad "CV7" smd circle
			(at -29.29001 27.900122 180)
			(size 0.450088 0.450088)
			(layers "F.Cu" "F.Mask" "F.Paste")
			(net "M_K_CPU0_SB_DQS_DP<7>")
		)
		(pad "CV8" smd circle
			(at -28.349956 27.900122 180)
			(size 0.450088 0.450088)
			(layers "F.Cu" "F.Mask" "F.Paste")
			(net "GND")
		)
		(pad "CV9" smd circle
			(at -27.409902 27.900122 180)
			(size 0.450088 0.450088)
			(layers "F.Cu" "F.Mask" "F.Paste")
			(net "M_L_CPU0_SB_DQ<20>")
		)
		(pad "CV10" smd circle
			(at -26.470102 27.900122 180)
			(size 0.450088 0.450088)
			(layers "F.Cu" "F.Mask" "F.Paste")
			(net "GND")
		)
		(pad "CV11" smd circle
			(at -25.530048 27.900122 180)
			(size 0.450088 0.450088)
			(layers "F.Cu" "F.Mask" "F.Paste")
			(net "M_L_CPU0_SB_DQS_DP<7>")
		)
		(pad "CV12" smd circle
			(at -24.589994 27.900122 180)
			(size 0.450088 0.450088)
			(layers "F.Cu" "F.Mask" "F.Paste")
			(net "GND")
		)
		(pad "CV13" smd circle
			(at -23.64994 27.900122 180)
			(size 0.450088 0.450088)
			(layers "F.Cu" "F.Mask" "F.Paste")
			(net "M_H_CPU0_SB_DQ<20>")
		)
		(pad "CV14" smd circle
			(at -22.709886 27.900122 180)
			(size 0.450088 0.450088)
			(layers "F.Cu" "F.Mask" "F.Paste")
			(net "M_H_CPU0_SB_DQS_DP<7>")
		)
		(pad "CV15" smd circle
			(at -21.770086 27.900122 180)
			(size 0.450088 0.450088)
			(layers "F.Cu" "F.Mask" "F.Paste")
			(net "GND")
		)
		(pad "CV16" smd circle
			(at -20.830032 27.900122 180)
			(size 0.450088 0.450088)
			(layers "F.Cu" "F.Mask" "F.Paste")
			(net "M_J_CPU0_SB_DQ<20>")
		)
		(pad "CV17" smd circle
			(at -19.889978 27.900122 180)
			(size 0.450088 0.450088)
			(layers "F.Cu" "F.Mask" "F.Paste")
			(net "GND")
		)
		(pad "CV18" smd circle
			(at -18.949924 27.900122 180)
			(size 0.450088 0.450088)
			(layers "F.Cu" "F.Mask" "F.Paste")
			(net "M_J_CPU0_SB_DQS_DP<7>")
		)
		(pad "CV19" smd circle
			(at -18.010124 27.900122 180)
			(size 0.450088 0.450088)
			(layers "F.Cu" "F.Mask" "F.Paste")
			(net "GND")
		)
		(pad "CV20" smd circle
			(at -17.07007 27.900122 180)
			(size 0.450088 0.450088)
			(layers "F.Cu" "F.Mask" "F.Paste")
			(net "M_I_CPU0_SB_DQ<20>")
		)
		(pad "CV21" smd circle
			(at -16.130016 27.900122 180)
			(size 0.450088 0.450088)
			(layers "F.Cu" "F.Mask" "F.Paste")
			(net "M_I_CPU0_SB_DQS_DP<7>")
		)
		(pad "CV22" smd circle
			(at -15.189962 27.900122 180)
			(size 0.450088 0.450088)
			(layers "F.Cu" "F.Mask" "F.Paste")
			(net "GND")
		)
		(pad "CV23" smd circle
			(at -14.249908 27.900122 180)
			(size 0.450088 0.450088)
			(layers "F.Cu" "F.Mask" "F.Paste")
			(net "PVDDCR_CPU1_P0")
		)
		(pad "CV24" smd circle
			(at -13.310108 27.900122 180)
			(size 0.450088 0.450088)
			(layers "F.Cu" "F.Mask" "F.Paste")
			(net "PVDDCR_CPU1_P0")
		)
		(pad "CV25" smd circle
			(at -12.370054 27.900122 180)
			(size 0.450088 0.450088)
			(layers "F.Cu" "F.Mask" "F.Paste")
			(net "GND")
		)
		(pad "CV26" smd circle
			(at -11.43 27.900122 180)
			(size 0.450088 0.450088)
			(layers "F.Cu" "F.Mask" "F.Paste")
			(net "PVDDCR_CPU1_P0")
		)
		(pad "CV27" smd circle
			(at -10.489946 27.900122 180)
			(size 0.450088 0.450088)
			(layers "F.Cu" "F.Mask" "F.Paste")
			(net "PVDDCR_CPU1_P0")
		)
		(pad "CV28" smd circle
			(at -9.549892 27.900122 180)
			(size 0.450088 0.450088)
			(layers "F.Cu" "F.Mask" "F.Paste")
			(net "GND")
		)
		(pad "CV29" smd circle
			(at -8.610092 27.900122 180)
			(size 0.450088 0.450088)
			(layers "F.Cu" "F.Mask" "F.Paste")
			(net "PVDDCR_CPU1_P0")
		)
		(pad "CV30" smd circle
			(at -7.670038 27.900122 180)
			(size 0.450088 0.450088)
			(layers "F.Cu" "F.Mask" "F.Paste")
			(net "PVDDCR_CPU1_P0")
		)
		(pad "CV31" smd circle
			(at -6.729984 27.900122 180)
			(size 0.450088 0.450088)
			(layers "F.Cu" "F.Mask" "F.Paste")
			(net "GND")
		)
		(pad "CV32" smd circle
			(at -5.78993 27.900122 180)
			(size 0.450088 0.450088)
			(layers "F.Cu" "F.Mask" "F.Paste")
			(net "PVDDCR_CPU1_P0")
		)
		(pad "CV33" smd circle
			(at -4.849876 27.900122 180)
			(size 0.450088 0.450088)
			(layers "F.Cu" "F.Mask" "F.Paste")
			(net "PVDDCR_CPU1_P0")
		)
		(pad "CV34" smd circle
			(at -3.910076 27.900122 180)
			(size 0.450088 0.450088)
			(layers "F.Cu" "F.Mask" "F.Paste")
			(net "GND")
		)
		(pad "CV35" smd circle
			(at -2.970022 27.900122 180)
			(size 0.450088 0.450088)
			(layers "F.Cu" "F.Mask" "F.Paste")
			(net "P5E_CPU0_P3_RX_DP<0>")
		)
		(pad "CV36" smd circle
			(at -2.029968 27.900122 180)
			(size 0.450088 0.450088)
			(layers "F.Cu" "F.Mask" "F.Paste")
			(net "P5E_CPU0_P3_RX_DN<0>")
		)
		(pad "CV37" smd circle
			(at -1.089914 27.900122 180)
			(size 0.450088 0.450088)
			(layers "F.Cu" "F.Mask" "F.Paste")
			(net "GND")
		)
		(pad "CV39" smd circle
			(at 0.78994 27.900122 180)
			(size 0.450088 0.450088)
			(layers "F.Cu" "F.Mask" "F.Paste")
			(net "GND")
		)
		(pad "CV40" smd circle
			(at 1.729994 27.900122 180)
			(size 0.450088 0.450088)
			(layers "F.Cu" "F.Mask" "F.Paste")
			(net "P5E_CPU0_P1_TX_DN<15>")
		)
		(pad "CV41" smd circle
			(at 2.670048 27.900122 180)
			(size 0.450088 0.450088)
			(layers "F.Cu" "F.Mask" "F.Paste")
			(net "P5E_CPU0_P1_TX_DP<15>")
		)
		(pad "CV42" smd circle
			(at 3.610102 27.900122 180)
			(size 0.450088 0.450088)
			(layers "F.Cu" "F.Mask" "F.Paste")
			(net "GND")
		)
		(pad "CV43" smd circle
			(at 4.549902 27.900122 180)
			(size 0.450088 0.450088)
			(layers "F.Cu" "F.Mask" "F.Paste")
			(net "PVDDCR_CPU1_P0")
		)
		(pad "CV44" smd circle
			(at 5.489956 27.900122 180)
			(size 0.450088 0.450088)
			(layers "F.Cu" "F.Mask" "F.Paste")
			(net "PVDDCR_CPU1_P0")
		)
		(pad "CV45" smd circle
			(at 6.43001 27.900122 180)
			(size 0.450088 0.450088)
			(layers "F.Cu" "F.Mask" "F.Paste")
			(net "GND")
		)
		(pad "CV46" smd circle
			(at 7.370064 27.900122 180)
			(size 0.450088 0.450088)
			(layers "F.Cu" "F.Mask" "F.Paste")
			(net "PVDDCR_CPU1_P0")
		)
		(pad "CV47" smd circle
			(at 8.310118 27.900122 180)
			(size 0.450088 0.450088)
			(layers "F.Cu" "F.Mask" "F.Paste")
			(net "PVDDCR_CPU1_P0")
		)
		(pad "CV48" smd circle
			(at 9.249918 27.900122 180)
			(size 0.450088 0.450088)
			(layers "F.Cu" "F.Mask" "F.Paste")
			(net "GND")
		)
		(pad "CV49" smd circle
			(at 10.189972 27.900122 180)
			(size 0.450088 0.450088)
			(layers "F.Cu" "F.Mask" "F.Paste")
			(net "PVDDCR_CPU1_P0")
		)
		(pad "CV50" smd circle
			(at 11.130026 27.900122 180)
			(size 0.450088 0.450088)
			(layers "F.Cu" "F.Mask" "F.Paste")
			(net "PVDDCR_CPU1_P0")
		)
		(pad "CV51" smd circle
			(at 12.07008 27.900122 180)
			(size 0.450088 0.450088)
			(layers "F.Cu" "F.Mask" "F.Paste")
			(net "GND")
		)
		(pad "CV52" smd circle
			(at 13.00988 27.900122 180)
			(size 0.450088 0.450088)
			(layers "F.Cu" "F.Mask" "F.Paste")
			(net "PVDDCR_CPU1_P0")
		)
		(pad "CV53" smd circle
			(at 13.949934 27.900122 180)
			(size 0.450088 0.450088)
			(layers "F.Cu" "F.Mask" "F.Paste")
			(net "PVDDCR_CPU1_P0")
		)
		(pad "CV54" smd circle
			(at 14.889988 27.900122 180)
			(size 0.450088 0.450088)
			(layers "F.Cu" "F.Mask" "F.Paste")
			(net "GND")
		)
		(pad "CV55" smd circle
			(at 15.830042 27.900122 180)
			(size 0.450088 0.450088)
			(layers "F.Cu" "F.Mask" "F.Paste")
			(net "M_C_CPU0_SB_DQS_DP<7>")
		)
		(pad "CV56" smd circle
			(at 16.770096 27.900122 180)
			(size 0.450088 0.450088)
			(layers "F.Cu" "F.Mask" "F.Paste")
			(net "M_C_CPU0_SB_DQ<20>")
		)
		(pad "CV57" smd circle
			(at 17.709896 27.900122 180)
			(size 0.450088 0.450088)
			(layers "F.Cu" "F.Mask" "F.Paste")
			(net "GND")
		)
		(pad "CV58" smd circle
			(at 18.64995 27.900122 180)
			(size 0.450088 0.450088)
			(layers "F.Cu" "F.Mask" "F.Paste")
			(net "M_D_CPU0_SB_DQS_DP<7>")
		)
		(pad "CV59" smd circle
			(at 19.590004 27.900122 180)
			(size 0.450088 0.450088)
			(layers "F.Cu" "F.Mask" "F.Paste")
			(net "GND")
		)
		(pad "CV60" smd circle
			(at 20.530058 27.900122 180)
			(size 0.450088 0.450088)
			(layers "F.Cu" "F.Mask" "F.Paste")
			(net "M_D_CPU0_SB_DQ<20>")
		)
		(pad "CV61" smd circle
			(at 21.470112 27.900122 180)
			(size 0.450088 0.450088)
			(layers "F.Cu" "F.Mask" "F.Paste")
			(net "GND")
		)
		(pad "CV62" smd circle
			(at 22.409912 27.900122 180)
			(size 0.450088 0.450088)
			(layers "F.Cu" "F.Mask" "F.Paste")
			(net "M_B_CPU0_SB_DQS_DP<7>")
		)
		(pad "CV63" smd circle
			(at 23.349966 27.900122 180)
			(size 0.450088 0.450088)
			(layers "F.Cu" "F.Mask" "F.Paste")
			(net "M_B_CPU0_SB_DQ<20>")
		)
		(pad "CV64" smd circle
			(at 24.29002 27.900122 180)
			(size 0.450088 0.450088)
			(layers "F.Cu" "F.Mask" "F.Paste")
			(net "GND")
		)
		(pad "CV65" smd circle
			(at 25.230074 27.900122 180)
			(size 0.450088 0.450088)
			(layers "F.Cu" "F.Mask" "F.Paste")
			(net "M_F_CPU0_SB_DQS_DP<7>")
		)
		(pad "CV66" smd circle
			(at 26.170128 27.900122 180)
			(size 0.450088 0.450088)
			(layers "F.Cu" "F.Mask" "F.Paste")
			(net "GND")
		)
		(pad "CV67" smd circle
			(at 27.109928 27.900122 180)
			(size 0.450088 0.450088)
			(layers "F.Cu" "F.Mask" "F.Paste")
			(net "M_F_CPU0_SB_DQ<20>")
		)
		(pad "CV68" smd circle
			(at 28.049982 27.900122 180)
			(size 0.450088 0.450088)
			(layers "F.Cu" "F.Mask" "F.Paste")
			(net "GND")
		)
		(pad "CV69" smd circle
			(at 28.990036 27.900122 180)
			(size 0.450088 0.450088)
			(layers "F.Cu" "F.Mask" "F.Paste")
			(net "M_E_CPU0_SB_DQS_DP<7>")
		)
		(pad "CV70" smd circle
			(at 29.93009 27.900122 180)
			(size 0.450088 0.450088)
			(layers "F.Cu" "F.Mask" "F.Paste")
			(net "M_E_CPU0_SB_DQ<20>")
		)
		(pad "CV71" smd circle
			(at 30.86989 27.900122 180)
			(size 0.450088 0.450088)
			(layers "F.Cu" "F.Mask" "F.Paste")
			(net "GND")
		)
		(pad "CV72" smd circle
			(at 31.809944 27.900122 180)
			(size 0.450088 0.450088)
			(layers "F.Cu" "F.Mask" "F.Paste")
			(net "M_A_CPU0_SB_DQS_DP<7>")
		)
		(pad "CV73" smd circle
			(at 32.749998 27.900122 180)
			(size 0.450088 0.450088)
			(layers "F.Cu" "F.Mask" "F.Paste")
			(net "GND")
		)
		(pad "CV74" smd circle
			(at 33.690052 27.900122 180)
			(size 0.450088 0.450088)
			(layers "F.Cu" "F.Mask" "F.Paste")
			(net "M_A_CPU0_SB_DQ<20>")
		)
		(pad "CW1" smd circle
			(at -34.459926 28.710128 180)
			(size 0.450088 0.450088)
			(layers "F.Cu" "F.Mask" "F.Paste")
			(net "GND")
		)
		(pad "CW2" smd circle
			(at -33.519872 28.710128 180)
			(size 0.450088 0.450088)
			(layers "F.Cu" "F.Mask" "F.Paste")
			(net "M_G_CPU0_SB_DQ<22>")
		)
		(pad "CW3" smd circle
			(at -32.580072 28.710128 180)
			(size 0.450088 0.450088)
			(layers "F.Cu" "F.Mask" "F.Paste")
			(net "M_G_CPU0_SB_DQ<21>")
		)
		(pad "CW4" smd circle
			(at -31.640018 28.710128 180)
			(size 0.450088 0.450088)
			(layers "F.Cu" "F.Mask" "F.Paste")
			(net "PVDD11_S3_P0")
		)
		(pad "CW5" smd circle
			(at -30.699964 28.710128 180)
			(size 0.450088 0.450088)
			(layers "F.Cu" "F.Mask" "F.Paste")
			(net "M_K_CPU0_SB_DQ<22>")
		)
	)
)
